Created on Valor NPI 9.6 Update 2 - Netlist Compare Summary.
DATE :  07 Feb 2017
TIME :  11:18:59


     MISMATCH SUMMARY REPORT
     -----------------------

Job  : 16368-sb                Job  : 16368-sb
Step : z                       Step : z
Type : CAD                     Type : CURCAD

-----------------------------------------------

 Mismatch Type: shorted


 Total : 0
-----------------------------------------------

 Mismatch Type: broken


 Total : 0
-----------------------------------------------

 Mismatch Type: missing


 Total : 0
-----------------------------------------------

 Mismatch Type: extra


 Total : 0
-----------------------------------------------
